FILE_TYPE = CONNECTIVITY;
{Allegro Design Entry HDL 17.4-2019 S026 (4007227) 1/17/2022}
"PAGE_NUMBER" = 406;
0"NC";
1"P5E_CPU0_P1_RX_BUF_DP<15:8>";
2"P5E_CPU0_P1_RX_BUF_DN<7:0>";
3"P5E_CPU0_P1_RX_BUF_DP<7:0>";
4"P5E_CPU0_P1_RX_BUF_DN<15:8>";
5"P5E_CPU0_P1_RX_BUF_DN<5>";
6"P5E_CPU0_P1_RX_BUF_DP<5>";
7"P5E_CPU0_P1_RX_BUF_DN<4>";
8"P5E_CPU0_P1_RX_BUF_DP<6>";
9"P5E_CPU0_P1_RX_BUF_DP<4>";
10"P5E_CPU0_P1_RX_BUF_DP<1>";
11"P5E_CPU0_P1_RX_BUF_DP<11>";
12"P5E_CPU0_P1_RX_BUF_DP<10>";
13"P5E_CPU0_P1_RX_BUF_DP<14>";
14"P5E_CPU0_P1_RX_BUF_DN<8>";
15"P5E_CPU0_P1_RX_BUF_DN<12>";
16"P5E_CPU0_P1_RX_BUF_DN<14>";
17"P5E_CPU0_P1_RX_BUF_DN<15>";
18"P5E_CPU0_P1_RX_BUF_DP<8>";
19"P5E_CPU0_P1_RX_BUF_DN<9>";
20"P5E_CPU0_P1_RX_BUF_DP<9>";
21"P5E_CPU0_P1_RX_BUF_DN<10>";
22"P5E_CPU0_P1_RX_BUF_DN<11>";
23"P5E_CPU0_P1_RX_BUF_DP<12>";
24"P5E_CPU0_P1_RX_BUF_DN<13>";
25"P5E_CPU0_P1_RX_BUF_DP<13>";
26"P5E_CPU0_P1_RX_BUF_DP<0>";
27"P5E_CPU0_P1_RX_BUF_DN<6>";
28"P5E_CPU0_P1_RX_BUF_DN<0>";
29"P5E_CPU0_P1_RX_BUF_DN<1>";
30"P5E_CPU0_P1_RX_BUF_DN<7>";
31"P5E_CPU0_P1_RX_BUF_DP<7>";
32"P5E_CPU0_P1_RX_BUF_DP<3>";
33"P5E_CPU0_P1_RX_BUF_DN<2>";
34"P5E_CPU0_P1_RX_BUF_DP<2>";
35"P5E_CPU0_P1_RX_BUF_DN<3>";
36"P5E_CPU0_P1_RX_BUF_DP<15>";
%"PT5161LRS"
"1","(-7875,4150)","0","pure_quanta","I1";
;
LOCATION"U6011"
$SEC"1"
CDS_SEC"1"
VALUE"PT5161LRS"
PART_TYPE"SMLF"
MATERIAL"IC"
NEEDS_NO_SIZE"TRUE"
CDS_LMAN_SYM_OUTLINE"-350,1450,300,-1400"
CDS_LIB"pure_quanta"
PART_NUMBER"AJ051610U03";
"A_PERN7"
$PN"CB2"14;
"A_PERP7"
$PN"CD1"18;
"A_PERN6"
$PN"BR2"19;
"A_PERP6"
$PN"BU1"20;
"A_PERN5"
$PN"BH2"21;
"A_PERP5"
$PN"BK1"12;
"A_PERN4"
$PN"BA2"22;
"A_PERP4"
$PN"BC1"11;
"A_PERN3"
$PN"AP2"15;
"A_PERP3"
$PN"AT1"23;
"A_PERN2"
$PN"AG2"24;
"A_PERP2"
$PN"AJ1"25;
"A_PERN1"
$PN"Y2"16;
"A_PERP1"
$PN"AB1"13;
"A_PERN0"
$PN"N2"17;
"A_PERP0"
$PN"R1"36;
%"TAP"
"1","(-6650,4250)","0","standard","I10";
;
CDS_LIB"standard"
BODY_TYPE"PLUMBING"
HDL_TAP"TRUE";
"B \NAC \NWC"4;
"S \NAC"
BN"12"15;
%"TAP"
"1","(-6850,4350)","0","standard","I11";
;
CDS_LIB"standard"
BODY_TYPE"PLUMBING"
HDL_TAP"TRUE";
"B \NAC \NWC"1;
"S \NAC"
BN"12"23;
%"TAP"
"1","(-6650,4600)","0","standard","I12";
;
CDS_LIB"standard"
BODY_TYPE"PLUMBING"
HDL_TAP"TRUE";
"B \NAC \NWC"4;
"S \NAC"
BN"13"24;
%"TAP"
"1","(-6850,4700)","0","standard","I13";
;
CDS_LIB"standard"
BODY_TYPE"PLUMBING"
HDL_TAP"TRUE";
"B \NAC \NWC"1;
"S \NAC"
BN"13"25;
%"TAP"
"1","(-6650,4950)","0","standard","I14";
;
CDS_LIB"standard"
BODY_TYPE"PLUMBING"
HDL_TAP"TRUE";
"B \NAC \NWC"4;
"S \NAC"
BN"14"16;
%"TAP"
"1","(-6850,5050)","0","standard","I15";
;
CDS_LIB"standard"
BODY_TYPE"PLUMBING"
HDL_TAP"TRUE";
"B \NAC \NWC"1;
"S \NAC"
BN"14"13;
%"TAP"
"1","(-6850,5400)","0","standard","I16";
;
CDS_LIB"standard"
BODY_TYPE"PLUMBING"
HDL_TAP"TRUE";
"B \NAC \NWC"1;
"S \NAC"
BN"15"36;
%"TAP"
"1","(-6650,5300)","0","standard","I17";
;
CDS_LIB"standard"
BODY_TYPE"PLUMBING"
HDL_TAP"TRUE";
"B \NAC \NWC"4;
"S \NAC"
BN"15"17;
%"TAP"
"1","(-6850,2950)","0","standard","I2";
;
CDS_LIB"standard"
BODY_TYPE"PLUMBING"
HDL_TAP"TRUE";
"B \NAC \NWC"1;
"S \NAC"
BN"8"18;
%"TAP"
"1","(-2400,2975)","0","standard","I20";
;
CDS_LIB"standard"
BODY_TYPE"PLUMBING"
HDL_TAP"TRUE";
"B \NAC \NWC"3;
"S \NAC"
BN"0"26;
%"TAP"
"1","(-2200,2875)","0","standard","I21";
;
CDS_LIB"standard"
BODY_TYPE"PLUMBING"
HDL_TAP"TRUE";
"B \NAC \NWC"2;
"S \NAC"
BN"0"28;
%"TAP"
"1","(-2400,3325)","0","standard","I22";
;
CDS_LIB"standard"
BODY_TYPE"PLUMBING"
HDL_TAP"TRUE";
"B \NAC \NWC"3;
"S \NAC"
BN"1"10;
%"TAP"
"1","(-2400,3675)","0","standard","I23";
;
CDS_LIB"standard"
BODY_TYPE"PLUMBING"
HDL_TAP"TRUE";
"B \NAC \NWC"3;
"S \NAC"
BN"2"34;
%"TAP"
"1","(-2400,4025)","0","standard","I24";
;
CDS_LIB"standard"
BODY_TYPE"PLUMBING"
HDL_TAP"TRUE";
"B \NAC \NWC"3;
"S \NAC"
BN"3"32;
%"TAP"
"1","(-2200,3225)","0","standard","I25";
;
CDS_LIB"standard"
BODY_TYPE"PLUMBING"
HDL_TAP"TRUE";
"B \NAC \NWC"2;
"S \NAC"
BN"1"29;
%"TAP"
"1","(-2200,3575)","0","standard","I26";
;
CDS_LIB"standard"
BODY_TYPE"PLUMBING"
HDL_TAP"TRUE";
"B \NAC \NWC"2;
"S \NAC"
BN"2"33;
%"TAP"
"1","(-2200,3925)","0","standard","I27";
;
CDS_LIB"standard"
BODY_TYPE"PLUMBING"
HDL_TAP"TRUE";
"B \NAC \NWC"2;
"S \NAC"
BN"3"35;
%"TAP"
"1","(-2400,4375)","0","standard","I28";
;
CDS_LIB"standard"
BODY_TYPE"PLUMBING"
HDL_TAP"TRUE";
"B \NAC \NWC"3;
"S \NAC"
BN"4"9;
%"TAP"
"1","(-2400,4725)","0","standard","I29";
;
CDS_LIB"standard"
BODY_TYPE"PLUMBING"
HDL_TAP"TRUE";
"B \NAC \NWC"3;
"S \NAC"
BN"5"6;
%"TAP"
"1","(-6650,2850)","0","standard","I3";
;
CDS_LIB"standard"
BODY_TYPE"PLUMBING"
HDL_TAP"TRUE";
"B \NAC \NWC"4;
"S \NAC"
BN"8"14;
%"TAP"
"1","(-2400,5075)","0","standard","I30";
;
CDS_LIB"standard"
BODY_TYPE"PLUMBING"
HDL_TAP"TRUE";
"B \NAC \NWC"3;
"S \NAC"
BN"6"8;
%"TAP"
"1","(-2200,4275)","0","standard","I31";
;
CDS_LIB"standard"
BODY_TYPE"PLUMBING"
HDL_TAP"TRUE";
"B \NAC \NWC"2;
"S \NAC"
BN"4"7;
%"TAP"
"1","(-2200,4625)","0","standard","I32";
;
CDS_LIB"standard"
BODY_TYPE"PLUMBING"
HDL_TAP"TRUE";
"B \NAC \NWC"2;
"S \NAC"
BN"5"5;
%"TAP"
"1","(-2200,4975)","0","standard","I33";
;
CDS_LIB"standard"
BODY_TYPE"PLUMBING"
HDL_TAP"TRUE";
"B \NAC \NWC"2;
"S \NAC"
BN"6"27;
%"TAP"
"1","(-2400,5425)","0","standard","I34";
;
CDS_LIB"standard"
BODY_TYPE"PLUMBING"
HDL_TAP"TRUE";
"B \NAC \NWC"3;
"S \NAC"
BN"7"31;
%"TAP"
"1","(-2200,5325)","0","standard","I35";
;
CDS_LIB"standard"
BODY_TYPE"PLUMBING"
HDL_TAP"TRUE";
"B \NAC \NWC"2;
"S \NAC"
BN"7"30;
%"PT5161LRS"
"2","(-3425,4175)","0","pure_quanta","I38";
;
LOCATION"U6011"
$SEC"2"
CDS_SEC"2"
PART_TYPE"SMLF"
MATERIAL"IC"
VALUE"PT5161LRS"
CDS_LIB"pure_quanta"
CDS_LMAN_SYM_OUTLINE"-350,1450,300,-1400"
NEEDS_NO_SIZE"TRUE"
PART_NUMBER"AJ051610U03";
"A_PERN15"
$PN"EV2"28;
"A_PERP15"
$PN"EY1"26;
"A_PERN14"
$PN"EL2"29;
"A_PERP14"
$PN"EN1"10;
"A_PERN13"
$PN"ED2"33;
"A_PERP13"
$PN"EF1"34;
"A_PERN12"
$PN"DU2"35;
"A_PERP12"
$PN"DW1"32;
"A_PERN11"
$PN"DK2"7;
"A_PERP11"
$PN"DM1"9;
"A_PERN10"
$PN"DC2"5;
"A_PERP10"
$PN"DE1"6;
"A_PERN9"
$PN"CT2"27;
"A_PERP9"
$PN"CV1"8;
"A_PERN8"
$PN"CJ2"30;
"A_PERP8"
$PN"CL1"31;
%"TAP"
"1","(-6850,3300)","0","standard","I4";
;
CDS_LIB"standard"
BODY_TYPE"PLUMBING"
HDL_TAP"TRUE";
"B \NAC \NWC"1;
"S \NAC"
BN"9"20;
%"TAP"
"1","(-6650,3200)","0","standard","I5";
;
CDS_LIB"standard"
BODY_TYPE"PLUMBING"
HDL_TAP"TRUE";
"B \NAC \NWC"4;
"S \NAC"
BN"9"19;
%"TAP"
"1","(-6850,3650)","0","standard","I6";
;
CDS_LIB"standard"
BODY_TYPE"PLUMBING"
HDL_TAP"TRUE";
"B \NAC \NWC"1;
"S \NAC"
BN"10"12;
%"TAP"
"1","(-6650,3550)","0","standard","I7";
;
CDS_LIB"standard"
BODY_TYPE"PLUMBING"
HDL_TAP"TRUE";
"B \NAC \NWC"4;
"S \NAC"
BN"10"21;
%"TAP"
"1","(-6650,3900)","0","standard","I8";
;
CDS_LIB"standard"
BODY_TYPE"PLUMBING"
HDL_TAP"TRUE";
"B \NAC \NWC"4;
"S \NAC"
BN"11"22;
%"TAP"
"1","(-6850,4000)","0","standard","I9";
;
CDS_LIB"standard"
BODY_TYPE"PLUMBING"
HDL_TAP"TRUE";
"B \NAC \NWC"1;
"S \NAC"
BN"11"11;
END.
